# T6G (Grand Teton) — schematic netlist excerpt (pin names and nets, part order shuffled) for the footprints in the layout excerpt that follows; sources: Cadence DE-HDL packaged netlist, KiCad conversion of 04192023_DAF0TMB3IC0_F0TG_MB_C_brd_V02_OCP.brd

PC361  Q_CAP  3300PF 50V 10% X7R  pkg 0402  page 217 : A = VSENSE_PVDDIO_P1_VSEN1 ; B = VSENSE_VSS_SENSE_B_P1
R1135  Q_RES  0 5% EMPTY  pkg 0402LF  page 247 : A = HP_LVC3_OCP_V3_1_R_EN ; B = HP_LVC3_OCP_V3_1_P12V_PWRGD
PC6013  Q_CAP  22UF 16V 20% X6S  pkg C0805  page 270 : A = SW_P12V_AUX_P1V2_AUX_FLT ; B = GND

(kicad_pcb
	(version 20260206)
	(generator "pcbnew")
	(generator_version "10.0")
	(general
		(thickness 1.6)
		(legacy_teardrops no)
	)
	(paper "A4")
	(title_block
		(title "04192023_DAF0TMB3IC0_F0TG_MB_C_brd_V02_OCP.brd")
		(comment 1 "Grand Teton / footprints 3475-3477 of 8354")
	)
	(layers
		(0 "F.Cu" signal "TOP")
		(4 "In1.Cu" signal "GND")
		(6 "In2.Cu" signal "IN1")
		(8 "In3.Cu" signal "GND1")
		(10 "In4.Cu" signal "IN2")
		(12 "In5.Cu" signal "GND2")
		(14 "In6.Cu" signal "IN3")
		(16 "In7.Cu" signal "GND3")
		(18 "In8.Cu" signal "VCC")
		(20 "In9.Cu" signal "VCC1")
		(22 "In10.Cu" signal "GND4")
		(24 "In11.Cu" signal "IN4")
		(26 "In12.Cu" signal "GND5")
		(28 "In13.Cu" signal "IN5")
		(30 "In14.Cu" signal "GND6")
		(32 "In15.Cu" signal "IN6")
		(34 "In16.Cu" signal "GND7")
		(2 "B.Cu" signal "BOTTOM")
		(9 "F.Adhes" user "F.Adhesive")
		(11 "B.Adhes" user "B.Adhesive")
		(13 "F.Paste" user "Package Geometry/Pastemask Top")
		(15 "B.Paste" user "Package Geometry/Pastemask Bottom")
		(5 "F.SilkS" user "Ref Des/Silkscreen Top")
		(7 "B.SilkS" user "Ref Des/Silkscreen Bottom")
		(1 "F.Mask" user "Board Geometry/Soldermask Top")
		(3 "B.Mask" user "Board Geometry/Soldermask Bottom")
		(17 "Dwgs.User" user "User.Drawings")
		(19 "Cmts.User" user "User.Comments")
		(21 "Eco1.User" user "User.Eco1")
		(23 "Eco2.User" user "User.Eco2")
		(25 "Edge.Cuts" user "Board Geometry/Outline")
		(27 "Margin" user)
		(31 "F.CrtYd" user "Package Geometry/Place Bound Top")
		(29 "B.CrtYd" user "Package Geometry/Place Bound Bottom")
		(35 "F.Fab" user "Ref Des/Assembly Top")
		(33 "B.Fab" user "Ref Des/Assembly Bottom")
	)
	(footprint ""
		(layer "F.Cu")
		(at 412.481268 -71.812912)
		(property "Reference" "R1135"
			(at 0 0 0)
			(layer "F.SilkS")
			(hide yes)
			(effects
				(font
					(size 1.27 1.27)
				)
			)
		)
		(property "Value" ""
			(at 0 0 0)
			(layer "F.Fab")
			(effects
				(font
					(size 1.27 1.27)
				)
			)
		)
		(duplicate_pad_numbers_are_jumpers no)
		(fp_line
			(start -0.7874 -0.4064)
			(end 0.7874 -0.4064)
			(stroke
				(width 0.1524)
				(type default)
			)
			(layer "F.SilkS")
		)
		(fp_line
			(start -0.7874 0.4064)
			(end -0.7874 -0.4064)
			(stroke
				(width 0.1524)
				(type default)
			)
			(layer "F.SilkS")
		)
		(fp_line
			(start 0.7874 -0.4064)
			(end 0.7874 0.4064)
			(stroke
				(width 0.1524)
				(type default)
			)
			(layer "F.SilkS")
		)
		(fp_line
			(start 0.7874 0.4064)
			(end -0.7874 0.4064)
			(stroke
				(width 0.1524)
				(type default)
			)
			(layer "F.SilkS")
		)
		(fp_line
			(start -0.67945 -0.305054)
			(end -0.12065 -0.305054)
			(stroke
				(width 0.1)
				(type default)
			)
			(layer "F.Fab")
		)
		(fp_line
			(start -0.67945 0.3048)
			(end -0.67945 -0.305054)
			(stroke
				(width 0.1)
				(type default)
			)
			(layer "F.Fab")
		)
		(fp_line
			(start -0.12065 -0.305054)
			(end -0.12065 -0.2794)
			(stroke
				(width 0.1)
				(type default)
			)
			(layer "F.Fab")
		)
		(fp_line
			(start -0.12065 -0.2794)
			(end 0.12065 -0.2794)
			(stroke
				(width 0.1)
				(type default)
			)
			(layer "F.Fab")
		)
		(fp_line
			(start -0.12065 0.2794)
			(end -0.12065 0.3048)
			(stroke
				(width 0.1)
				(type default)
			)
			(layer "F.Fab")
		)
		(fp_line
			(start -0.12065 0.3048)
			(end -0.67945 0.3048)
			(stroke
				(width 0.1)
				(type default)
			)
			(layer "F.Fab")
		)
		(fp_line
			(start 0.120396 0.2794)
			(end -0.12065 0.2794)
			(stroke
				(width 0.1)
				(type default)
			)
			(layer "F.Fab")
		)
		(fp_line
			(start 0.120396 0.3048)
			(end 0.120396 0.2794)
			(stroke
				(width 0.1)
				(type default)
			)
			(layer "F.Fab")
		)
		(fp_line
			(start 0.12065 -0.3048)
			(end 0.67945 -0.3048)
			(stroke
				(width 0.1)
				(type default)
			)
			(layer "F.Fab")
		)
		(fp_line
			(start 0.12065 -0.2794)
			(end 0.12065 -0.3048)
			(stroke
				(width 0.1)
				(type default)
			)
			(layer "F.Fab")
		)
		(fp_line
			(start 0.67945 -0.3048)
			(end 0.67945 0.3048)
			(stroke
				(width 0.1)
				(type default)
			)
			(layer "F.Fab")
		)
		(fp_line
			(start 0.67945 0.3048)
			(end 0.120396 0.3048)
			(stroke
				(width 0.1)
				(type default)
			)
			(layer "F.Fab")
		)
		(pad "1" smd circle
			(at -0.40005 0)
			(size 0 0)
			(layers "F.Cu" "F.Mask" "F.Paste")
			(net "HP_LVC3_OCP_V3_1_R_EN")
		)
		(pad "2" smd circle
			(at 0.40005 0)
			(size 0 0)
			(layers "F.Cu" "F.Mask" "F.Paste")
			(net "HP_LVC3_OCP_V3_1_P12V_PWRGD")
		)
	)
	(footprint ""
		(layer "F.Cu")
		(at 36.195 -360.045 180)
		(property "Reference" "PC361"
			(at 0 0 180)
			(layer "F.SilkS")
			(hide yes)
			(effects
				(font
					(size 1.27 1.27)
				)
			)
		)
		(property "Value" ""
			(at 0 0 180)
			(layer "F.Fab")
			(effects
				(font
					(size 1.27 1.27)
				)
			)
		)
		(duplicate_pad_numbers_are_jumpers no)
		(fp_line
			(start 0.7874 0.4064)
			(end -0.7874 0.4064)
			(stroke
				(width 0.1524)
				(type default)
			)
			(layer "F.SilkS")
		)
		(fp_line
			(start 0.7874 -0.4064)
			(end 0.7874 0.4064)
			(stroke
				(width 0.1524)
				(type default)
			)
			(layer "F.SilkS")
		)
		(fp_line
			(start -0.7874 0.4064)
			(end -0.7874 -0.4064)
			(stroke
				(width 0.1524)
				(type default)
			)
			(layer "F.SilkS")
		)
		(fp_line
			(start -0.7874 -0.4064)
			(end 0.7874 -0.4064)
			(stroke
				(width 0.1524)
				(type default)
			)
			(layer "F.SilkS")
		)
		(fp_line
			(start 0.67945 0.3048)
			(end 0.120396 0.3048)
			(stroke
				(width 0.1)
				(type default)
			)
			(layer "F.Fab")
		)
		(fp_line
			(start 0.67945 -0.3048)
			(end 0.67945 0.3048)
			(stroke
				(width 0.1)
				(type default)
			)
			(layer "F.Fab")
		)
		(fp_line
			(start 0.12065 -0.2794)
			(end 0.12065 -0.3048)
			(stroke
				(width 0.1)
				(type default)
			)
			(layer "F.Fab")
		)
		(fp_line
			(start 0.12065 -0.3048)
			(end 0.67945 -0.3048)
			(stroke
				(width 0.1)
				(type default)
			)
			(layer "F.Fab")
		)
		(fp_line
			(start 0.120396 0.3048)
			(end 0.120396 0.2794)
			(stroke
				(width 0.1)
				(type default)
			)
			(layer "F.Fab")
		)
		(fp_line
			(start 0.120396 0.2794)
			(end -0.12065 0.2794)
			(stroke
				(width 0.1)
				(type default)
			)
			(layer "F.Fab")
		)
		(fp_line
			(start -0.12065 0.3048)
			(end -0.67945 0.3048)
			(stroke
				(width 0.1)
				(type default)
			)
			(layer "F.Fab")
		)
		(fp_line
			(start -0.12065 0.2794)
			(end -0.12065 0.3048)
			(stroke
				(width 0.1)
				(type default)
			)
			(layer "F.Fab")
		)
		(fp_line
			(start -0.12065 -0.2794)
			(end 0.12065 -0.2794)
			(stroke
				(width 0.1)
				(type default)
			)
			(layer "F.Fab")
		)
		(fp_line
			(start -0.12065 -0.305054)
			(end -0.12065 -0.2794)
			(stroke
				(width 0.1)
				(type default)
			)
			(layer "F.Fab")
		)
		(fp_line
			(start -0.67945 0.3048)
			(end -0.67945 -0.305054)
			(stroke
				(width 0.1)
				(type default)
			)
			(layer "F.Fab")
		)
		(fp_line
			(start -0.67945 -0.305054)
			(end -0.12065 -0.305054)
			(stroke
				(width 0.1)
				(type default)
			)
			(layer "F.Fab")
		)
		(pad "1" smd circle
			(at -0.40005 0 180)
			(size 0 0)
			(layers "F.Cu" "F.Mask" "F.Paste")
			(net "VSENSE_PVDDIO_P1_VSEN1")
		)
		(pad "2" smd circle
			(at 0.40005 0 180)
			(size 0 0)
			(layers "F.Cu" "F.Mask" "F.Paste")
			(net "VSENSE_VSS_SENSE_B_P1")
		)
	)
	(footprint ""
		(layer "F.Cu")
		(at 117.792754 -76.987654 90)
		(property "Reference" "PC6013"
			(at 0 0 90)
			(layer "F.SilkS")
			(hide yes)
			(effects
				(font
					(size 1.27 1.27)
				)
			)
		)
		(property "Value" ""
			(at 0 0 90)
			(layer "F.Fab")
			(effects
				(font
					(size 1.27 1.27)
				)
			)
		)
		(duplicate_pad_numbers_are_jumpers no)
		(fp_line
			(start 1.524 -0.762)
			(end 1.524 0.762)
			(stroke
				(width 0.1524)
				(type default)
			)
			(layer "F.SilkS")
		)
		(fp_line
			(start -1.524 -0.762)
			(end 1.524 -0.762)
			(stroke
				(width 0.1524)
				(type default)
			)
			(layer "F.SilkS")
		)
		(fp_line
			(start 1.524 0.762)
			(end -1.524 0.762)
			(stroke
				(width 0.1524)
				(type default)
			)
			(layer "F.SilkS")
		)
		(fp_line
			(start -1.524 0.762)
			(end -1.524 -0.762)
			(stroke
				(width 0.1524)
				(type default)
			)
			(layer "F.SilkS")
		)
		(fp_line
			(start 1.1049 -0.724916)
			(end -1.1049 -0.724916)
			(stroke
				(width 0.1)
				(type default)
			)
			(layer "F.Fab")
		)
		(fp_line
			(start -1.1049 -0.724916)
			(end -1.1049 0.724916)
			(stroke
				(width 0.1)
				(type default)
			)
			(layer "F.Fab")
		)
		(fp_line
			(start 1.1049 0.724916)
			(end 1.1049 -0.724916)
			(stroke
				(width 0.1)
				(type default)
			)
			(layer "F.Fab")
		)
		(fp_line
			(start -1.1049 0.724916)
			(end 1.1049 0.724916)
			(stroke
				(width 0.1)
				(type default)
			)
			(layer "F.Fab")
		)
		(pad "1" smd rect
			(at -0.889 0 270)
			(size 1.016 1.27)
			(layers "F.Cu" "F.Mask" "F.Paste")
			(net "SW_P12V_AUX_P1V2_AUX_FLT")
		)
		(pad "2" smd rect
			(at 0.889 0 270)
			(size 1.016 1.27)
			(layers "F.Cu" "F.Mask" "F.Paste")
			(net "GND")
		)
	)
)
